# SI test board — assets/stackup.csv
Name;Type;Material;Thickness[mm];Constant
F.Mask;Top Solder Mask;;0.01;
F.Cu;copper;;0.035;
dielectric 1;core;FR4;0.12;4.18
In1.Cu;copper;;0.035;
dielectric 2;prepreg;FR4;1.2;4.18
In2.Cu;copper;;0.035;
dielectric 3;core;FR4;0.12;4.18
B.Cu;copper;;0.035;
B.Mask;Bottom Solder Mask;;0.01;
